# T6G (Grand Teton) — schematic netlist excerpt (pin names and nets, part order shuffled) for the footprints in the layout excerpt that follows; sources: Cadence DE-HDL packaged netlist, KiCad conversion of 04192023_DAF0TMB3IC0_F0TG_MB_C_brd_V02_OCP.brd

R3089  Q_RES  130 1% CHIP  pkg 0402LF  page 255 : A = LED_PWRGD_PVDDCR_SOC_P0_R ; B = P3V3_AUX
R890  Q_RES  10K 5% EMPTY  pkg 0402LF  page 151 : A = P3V3_AUX ; B = SCM_SPARE_1
PC518_2  Q_CAP  22UF 16V 20% X6S  pkg C0805  page 225 : A = SW_P12V_AUX_PVDD11_S3_P1_FLT ; B = GND

(kicad_pcb
	(version 20260206)
	(generator "pcbnew")
	(generator_version "10.0")
	(general
		(thickness 1.6)
		(legacy_teardrops no)
	)
	(paper "A4")
	(title_block
		(title "04192023_DAF0TMB3IC0_F0TG_MB_C_brd_V02_OCP.brd")
		(comment 1 "Grand Teton / footprints 6770-6772 of 8354")
	)
	(layers
		(0 "F.Cu" signal "TOP")
		(4 "In1.Cu" signal "GND")
		(6 "In2.Cu" signal "IN1")
		(8 "In3.Cu" signal "GND1")
		(10 "In4.Cu" signal "IN2")
		(12 "In5.Cu" signal "GND2")
		(14 "In6.Cu" signal "IN3")
		(16 "In7.Cu" signal "GND3")
		(18 "In8.Cu" signal "VCC")
		(20 "In9.Cu" signal "VCC1")
		(22 "In10.Cu" signal "GND4")
		(24 "In11.Cu" signal "IN4")
		(26 "In12.Cu" signal "GND5")
		(28 "In13.Cu" signal "IN5")
		(30 "In14.Cu" signal "GND6")
		(32 "In15.Cu" signal "IN6")
		(34 "In16.Cu" signal "GND7")
		(2 "B.Cu" signal "BOTTOM")
		(9 "F.Adhes" user "F.Adhesive")
		(11 "B.Adhes" user "B.Adhesive")
		(13 "F.Paste" user "Package Geometry/Pastemask Top")
		(15 "B.Paste" user "Package Geometry/Pastemask Bottom")
		(5 "F.SilkS" user "Ref Des/Silkscreen Top")
		(7 "B.SilkS" user "Ref Des/Silkscreen Bottom")
		(1 "F.Mask" user "Board Geometry/Soldermask Top")
		(3 "B.Mask" user "Board Geometry/Soldermask Bottom")
		(17 "Dwgs.User" user "User.Drawings")
		(19 "Cmts.User" user "User.Comments")
		(21 "Eco1.User" user "User.Eco1")
		(23 "Eco2.User" user "User.Eco2")
		(25 "Edge.Cuts" user "Board Geometry/Outline")
		(27 "Margin" user)
		(31 "F.CrtYd" user "Package Geometry/Place Bound Top")
		(29 "B.CrtYd" user "Package Geometry/Place Bound Bottom")
		(35 "F.Fab" user "Ref Des/Assembly Top")
		(33 "B.Fab" user "Ref Des/Assembly Bottom")
	)
	(footprint ""
		(layer "B.Cu")
		(at 167.132 -118.328948 180)
		(property "Reference" "R890"
			(at 0 0 0)
			(layer "B.SilkS")
			(hide yes)
			(effects
				(font
					(size 1.27 1.27)
				)
				(justify mirror)
			)
		)
		(property "Value" ""
			(at 0 0 0)
			(layer "B.Fab")
			(effects
				(font
					(size 1.27 1.27)
				)
				(justify mirror)
			)
		)
		(duplicate_pad_numbers_are_jumpers no)
		(fp_line
			(start 0.7874 0.4064)
			(end 0.7874 -0.4064)
			(stroke
				(width 0.1524)
				(type default)
			)
			(layer "B.SilkS")
		)
		(fp_line
			(start 0.7874 -0.4064)
			(end -0.7874 -0.4064)
			(stroke
				(width 0.1524)
				(type default)
			)
			(layer "B.SilkS")
		)
		(fp_line
			(start -0.7874 0.4064)
			(end 0.7874 0.4064)
			(stroke
				(width 0.1524)
				(type default)
			)
			(layer "B.SilkS")
		)
		(fp_line
			(start -0.7874 -0.4064)
			(end -0.7874 0.4064)
			(stroke
				(width 0.1524)
				(type default)
			)
			(layer "B.SilkS")
		)
		(fp_line
			(start 0.67945 0.3048)
			(end 0.67945 -0.305054)
			(stroke
				(width 0.1)
				(type default)
			)
			(layer "B.Fab")
		)
		(fp_line
			(start 0.67945 -0.305054)
			(end 0.12065 -0.305054)
			(stroke
				(width 0.1)
				(type default)
			)
			(layer "B.Fab")
		)
		(fp_line
			(start 0.12065 0.3048)
			(end 0.67945 0.3048)
			(stroke
				(width 0.1)
				(type default)
			)
			(layer "B.Fab")
		)
		(fp_line
			(start 0.12065 0.2794)
			(end 0.12065 0.3048)
			(stroke
				(width 0.1)
				(type default)
			)
			(layer "B.Fab")
		)
		(fp_line
			(start 0.12065 -0.2794)
			(end -0.12065 -0.2794)
			(stroke
				(width 0.1)
				(type default)
			)
			(layer "B.Fab")
		)
		(fp_line
			(start 0.12065 -0.305054)
			(end 0.12065 -0.2794)
			(stroke
				(width 0.1)
				(type default)
			)
			(layer "B.Fab")
		)
		(fp_line
			(start -0.120396 0.3048)
			(end -0.120396 0.2794)
			(stroke
				(width 0.1)
				(type default)
			)
			(layer "B.Fab")
		)
		(fp_line
			(start -0.120396 0.2794)
			(end 0.12065 0.2794)
			(stroke
				(width 0.1)
				(type default)
			)
			(layer "B.Fab")
		)
		(fp_line
			(start -0.12065 -0.2794)
			(end -0.12065 -0.3048)
			(stroke
				(width 0.1)
				(type default)
			)
			(layer "B.Fab")
		)
		(fp_line
			(start -0.12065 -0.3048)
			(end -0.67945 -0.3048)
			(stroke
				(width 0.1)
				(type default)
			)
			(layer "B.Fab")
		)
		(fp_line
			(start -0.67945 0.3048)
			(end -0.120396 0.3048)
			(stroke
				(width 0.1)
				(type default)
			)
			(layer "B.Fab")
		)
		(fp_line
			(start -0.67945 -0.3048)
			(end -0.67945 0.3048)
			(stroke
				(width 0.1)
				(type default)
			)
			(layer "B.Fab")
		)
		(pad "1" smd circle
			(at 0.40005 0)
			(size 0 0)
			(layers "B.Cu" "B.Mask" "B.Paste")
			(net "P3V3_AUX")
		)
		(pad "2" smd circle
			(at -0.40005 0)
			(size 0 0)
			(layers "B.Cu" "B.Mask" "B.Paste")
			(net "SCM_SPARE_1")
		)
	)
	(footprint ""
		(layer "B.Cu")
		(at 326.667876 -66.708782 90)
		(property "Reference" "R3089"
			(at 0 0 90)
			(layer "B.SilkS")
			(hide yes)
			(effects
				(font
					(size 1.27 1.27)
				)
				(justify mirror)
			)
		)
		(property "Value" ""
			(at 0 0 90)
			(layer "B.Fab")
			(effects
				(font
					(size 1.27 1.27)
				)
				(justify mirror)
			)
		)
		(duplicate_pad_numbers_are_jumpers no)
		(fp_line
			(start 0.7874 -0.4064)
			(end -0.7874 -0.4064)
			(stroke
				(width 0.1524)
				(type default)
			)
			(layer "B.SilkS")
		)
		(fp_line
			(start -0.7874 -0.4064)
			(end -0.7874 0.4064)
			(stroke
				(width 0.1524)
				(type default)
			)
			(layer "B.SilkS")
		)
		(fp_line
			(start 0.7874 0.4064)
			(end 0.7874 -0.4064)
			(stroke
				(width 0.1524)
				(type default)
			)
			(layer "B.SilkS")
		)
		(fp_line
			(start -0.7874 0.4064)
			(end 0.7874 0.4064)
			(stroke
				(width 0.1524)
				(type default)
			)
			(layer "B.SilkS")
		)
		(fp_line
			(start 0.67945 -0.305054)
			(end 0.12065 -0.305054)
			(stroke
				(width 0.1)
				(type default)
			)
			(layer "B.Fab")
		)
		(fp_line
			(start 0.12065 -0.305054)
			(end 0.12065 -0.2794)
			(stroke
				(width 0.1)
				(type default)
			)
			(layer "B.Fab")
		)
		(fp_line
			(start -0.12065 -0.3048)
			(end -0.67945 -0.3048)
			(stroke
				(width 0.1)
				(type default)
			)
			(layer "B.Fab")
		)
		(fp_line
			(start -0.67945 -0.3048)
			(end -0.67945 0.3048)
			(stroke
				(width 0.1)
				(type default)
			)
			(layer "B.Fab")
		)
		(fp_line
			(start 0.12065 -0.2794)
			(end -0.12065 -0.2794)
			(stroke
				(width 0.1)
				(type default)
			)
			(layer "B.Fab")
		)
		(fp_line
			(start -0.12065 -0.2794)
			(end -0.12065 -0.3048)
			(stroke
				(width 0.1)
				(type default)
			)
			(layer "B.Fab")
		)
		(fp_line
			(start 0.12065 0.2794)
			(end 0.12065 0.3048)
			(stroke
				(width 0.1)
				(type default)
			)
			(layer "B.Fab")
		)
		(fp_line
			(start -0.120396 0.2794)
			(end 0.12065 0.2794)
			(stroke
				(width 0.1)
				(type default)
			)
			(layer "B.Fab")
		)
		(fp_line
			(start 0.67945 0.3048)
			(end 0.67945 -0.305054)
			(stroke
				(width 0.1)
				(type default)
			)
			(layer "B.Fab")
		)
		(fp_line
			(start 0.12065 0.3048)
			(end 0.67945 0.3048)
			(stroke
				(width 0.1)
				(type default)
			)
			(layer "B.Fab")
		)
		(fp_line
			(start -0.120396 0.3048)
			(end -0.120396 0.2794)
			(stroke
				(width 0.1)
				(type default)
			)
			(layer "B.Fab")
		)
		(fp_line
			(start -0.67945 0.3048)
			(end -0.120396 0.3048)
			(stroke
				(width 0.1)
				(type default)
			)
			(layer "B.Fab")
		)
		(pad "1" smd circle
			(at 0.40005 0 270)
			(size 0 0)
			(layers "B.Cu" "B.Mask" "B.Paste")
			(net "LED_PWRGD_PVDDCR_SOC_P0_R")
		)
		(pad "2" smd circle
			(at -0.40005 0 270)
			(size 0 0)
			(layers "B.Cu" "B.Mask" "B.Paste")
			(net "P3V3_AUX")
		)
	)
	(footprint ""
		(layer "B.Cu")
		(at 192.511426 -355.078284 -90)
		(property "Reference" "PC518_2"
			(at 0 0 90)
			(layer "B.SilkS")
			(hide yes)
			(effects
				(font
					(size 1.27 1.27)
				)
				(justify mirror)
			)
		)
		(property "Value" ""
			(at 0 0 90)
			(layer "B.Fab")
			(effects
				(font
					(size 1.27 1.27)
				)
				(justify mirror)
			)
		)
		(duplicate_pad_numbers_are_jumpers no)
		(fp_line
			(start -1.524 0.762)
			(end 1.524 0.762)
			(stroke
				(width 0.1524)
				(type default)
			)
			(layer "B.SilkS")
		)
		(fp_line
			(start 1.524 0.762)
			(end 1.524 -0.762)
			(stroke
				(width 0.1524)
				(type default)
			)
			(layer "B.SilkS")
		)
		(fp_line
			(start -1.524 -0.762)
			(end -1.524 0.762)
			(stroke
				(width 0.1524)
				(type default)
			)
			(layer "B.SilkS")
		)
		(fp_line
			(start 1.524 -0.762)
			(end -1.524 -0.762)
			(stroke
				(width 0.1524)
				(type default)
			)
			(layer "B.SilkS")
		)
		(fp_line
			(start -1.1049 0.724916)
			(end -1.1049 -0.724916)
			(stroke
				(width 0.1)
				(type default)
			)
			(layer "B.Fab")
		)
		(fp_line
			(start 1.1049 0.724916)
			(end -1.1049 0.724916)
			(stroke
				(width 0.1)
				(type default)
			)
			(layer "B.Fab")
		)
		(fp_line
			(start -1.1049 -0.724916)
			(end 1.1049 -0.724916)
			(stroke
				(width 0.1)
				(type default)
			)
			(layer "B.Fab")
		)
		(fp_line
			(start 1.1049 -0.724916)
			(end 1.1049 0.724916)
			(stroke
				(width 0.1)
				(type default)
			)
			(layer "B.Fab")
		)
		(pad "1" smd rect
			(at 0.889 0 270)
			(size 1.016 1.27)
			(layers "B.Cu" "B.Mask" "B.Paste")
			(net "SW_P12V_AUX_PVDD11_S3_P1_FLT")
		)
		(pad "2" smd rect
			(at -0.889 0 270)
			(size 1.016 1.27)
			(layers "B.Cu" "B.Mask" "B.Paste")
			(net "GND")
		)
	)
)
